# T6G (Grand Teton) — schematic netlist excerpt (pin names and nets, part order shuffled) for the footprints in the layout excerpt that follows; sources: Cadence DE-HDL packaged netlist, KiCad conversion of 04192023_DAF0TMB3IC0_F0TG_MB_C_brd_V02_OCP.brd

R121  Q_RES  0 5% CHIP  pkg 0402LF  page 238 : A = SMB_FRU_3V3AUX_SCL ; B = SMB_CPU_FRU_3V3AUX_SCL
R1631  Q_RES  33 5% CHIP  pkg 0402LF  page 172 : A = HDT_HDR_DBREQ_R_N ; B = HDT_HDR_DBREQ_N

(kicad_pcb
	(version 20260206)
	(generator "pcbnew")
	(generator_version "10.0")
	(general
		(thickness 1.6)
		(legacy_teardrops no)
	)
	(paper "A4")
	(title_block
		(title "04192023_DAF0TMB3IC0_F0TG_MB_C_brd_V02_OCP.brd")
		(comment 1 "Grand Teton / footprints 4484-4485 of 8354")
	)
	(layers
		(0 "F.Cu" signal "TOP")
		(4 "In1.Cu" signal "GND")
		(6 "In2.Cu" signal "IN1")
		(8 "In3.Cu" signal "GND1")
		(10 "In4.Cu" signal "IN2")
		(12 "In5.Cu" signal "GND2")
		(14 "In6.Cu" signal "IN3")
		(16 "In7.Cu" signal "GND3")
		(18 "In8.Cu" signal "VCC")
		(20 "In9.Cu" signal "VCC1")
		(22 "In10.Cu" signal "GND4")
		(24 "In11.Cu" signal "IN4")
		(26 "In12.Cu" signal "GND5")
		(28 "In13.Cu" signal "IN5")
		(30 "In14.Cu" signal "GND6")
		(32 "In15.Cu" signal "IN6")
		(34 "In16.Cu" signal "GND7")
		(2 "B.Cu" signal "BOTTOM")
		(9 "F.Adhes" user "F.Adhesive")
		(11 "B.Adhes" user "B.Adhesive")
		(13 "F.Paste" user "Package Geometry/Pastemask Top")
		(15 "B.Paste" user "Package Geometry/Pastemask Bottom")
		(5 "F.SilkS" user "Ref Des/Silkscreen Top")
		(7 "B.SilkS" user "Ref Des/Silkscreen Bottom")
		(1 "F.Mask" user "Board Geometry/Soldermask Top")
		(3 "B.Mask" user "Board Geometry/Soldermask Bottom")
		(17 "Dwgs.User" user "User.Drawings")
		(19 "Cmts.User" user "User.Comments")
		(21 "Eco1.User" user "User.Eco1")
		(23 "Eco2.User" user "User.Eco2")
		(25 "Edge.Cuts" user "Board Geometry/Outline")
		(27 "Margin" user)
		(31 "F.CrtYd" user "Package Geometry/Place Bound Top")
		(29 "B.CrtYd" user "Package Geometry/Place Bound Bottom")
		(35 "F.Fab" user "Ref Des/Assembly Top")
		(33 "B.Fab" user "Ref Des/Assembly Bottom")
	)
	(footprint ""
		(layer "F.Cu")
		(at 314.567316 -111.57077 180)
		(property "Reference" "R121"
			(at 0 0 180)
			(layer "F.SilkS")
			(hide yes)
			(effects
				(font
					(size 1.27 1.27)
				)
			)
		)
		(property "Value" ""
			(at 0 0 180)
			(layer "F.Fab")
			(effects
				(font
					(size 1.27 1.27)
				)
			)
		)
		(duplicate_pad_numbers_are_jumpers no)
		(fp_line
			(start 0.7874 0.4064)
			(end -0.7874 0.4064)
			(stroke
				(width 0.1524)
				(type default)
			)
			(layer "F.SilkS")
		)
		(fp_line
			(start 0.7874 -0.4064)
			(end 0.7874 0.4064)
			(stroke
				(width 0.1524)
				(type default)
			)
			(layer "F.SilkS")
		)
		(fp_line
			(start -0.7874 0.4064)
			(end -0.7874 -0.4064)
			(stroke
				(width 0.1524)
				(type default)
			)
			(layer "F.SilkS")
		)
		(fp_line
			(start -0.7874 -0.4064)
			(end 0.7874 -0.4064)
			(stroke
				(width 0.1524)
				(type default)
			)
			(layer "F.SilkS")
		)
		(fp_line
			(start 0.67945 0.3048)
			(end 0.120396 0.3048)
			(stroke
				(width 0.1)
				(type default)
			)
			(layer "F.Fab")
		)
		(fp_line
			(start 0.67945 -0.3048)
			(end 0.67945 0.3048)
			(stroke
				(width 0.1)
				(type default)
			)
			(layer "F.Fab")
		)
		(fp_line
			(start 0.12065 -0.2794)
			(end 0.12065 -0.3048)
			(stroke
				(width 0.1)
				(type default)
			)
			(layer "F.Fab")
		)
		(fp_line
			(start 0.12065 -0.3048)
			(end 0.67945 -0.3048)
			(stroke
				(width 0.1)
				(type default)
			)
			(layer "F.Fab")
		)
		(fp_line
			(start 0.120396 0.3048)
			(end 0.120396 0.2794)
			(stroke
				(width 0.1)
				(type default)
			)
			(layer "F.Fab")
		)
		(fp_line
			(start 0.120396 0.2794)
			(end -0.12065 0.2794)
			(stroke
				(width 0.1)
				(type default)
			)
			(layer "F.Fab")
		)
		(fp_line
			(start -0.12065 0.3048)
			(end -0.67945 0.3048)
			(stroke
				(width 0.1)
				(type default)
			)
			(layer "F.Fab")
		)
		(fp_line
			(start -0.12065 0.2794)
			(end -0.12065 0.3048)
			(stroke
				(width 0.1)
				(type default)
			)
			(layer "F.Fab")
		)
		(fp_line
			(start -0.12065 -0.2794)
			(end 0.12065 -0.2794)
			(stroke
				(width 0.1)
				(type default)
			)
			(layer "F.Fab")
		)
		(fp_line
			(start -0.12065 -0.305054)
			(end -0.12065 -0.2794)
			(stroke
				(width 0.1)
				(type default)
			)
			(layer "F.Fab")
		)
		(fp_line
			(start -0.67945 0.3048)
			(end -0.67945 -0.305054)
			(stroke
				(width 0.1)
				(type default)
			)
			(layer "F.Fab")
		)
		(fp_line
			(start -0.67945 -0.305054)
			(end -0.12065 -0.305054)
			(stroke
				(width 0.1)
				(type default)
			)
			(layer "F.Fab")
		)
		(pad "1" smd circle
			(at -0.40005 0 180)
			(size 0 0)
			(layers "F.Cu" "F.Mask" "F.Paste")
			(net "SMB_FRU_3V3AUX_SCL")
		)
		(pad "2" smd circle
			(at 0.40005 0 180)
			(size 0 0)
			(layers "F.Cu" "F.Mask" "F.Paste")
			(net "SMB_CPU_FRU_3V3AUX_SCL")
		)
	)
	(footprint ""
		(layer "F.Cu")
		(at 386.211826 -62.0395 180)
		(property "Reference" "R1631"
			(at 0 0 180)
			(layer "F.SilkS")
			(hide yes)
			(effects
				(font
					(size 1.27 1.27)
				)
			)
		)
		(property "Value" ""
			(at 0 0 180)
			(layer "F.Fab")
			(effects
				(font
					(size 1.27 1.27)
				)
			)
		)
		(duplicate_pad_numbers_are_jumpers no)
		(fp_line
			(start 0.7874 0.4064)
			(end -0.7874 0.4064)
			(stroke
				(width 0.1524)
				(type default)
			)
			(layer "F.SilkS")
		)
		(fp_line
			(start 0.7874 -0.4064)
			(end 0.7874 0.4064)
			(stroke
				(width 0.1524)
				(type default)
			)
			(layer "F.SilkS")
		)
		(fp_line
			(start -0.7874 0.4064)
			(end -0.7874 -0.4064)
			(stroke
				(width 0.1524)
				(type default)
			)
			(layer "F.SilkS")
		)
		(fp_line
			(start -0.7874 -0.4064)
			(end 0.7874 -0.4064)
			(stroke
				(width 0.1524)
				(type default)
			)
			(layer "F.SilkS")
		)
		(fp_line
			(start 0.67945 0.3048)
			(end 0.120396 0.3048)
			(stroke
				(width 0.1)
				(type default)
			)
			(layer "F.Fab")
		)
		(fp_line
			(start 0.67945 -0.3048)
			(end 0.67945 0.3048)
			(stroke
				(width 0.1)
				(type default)
			)
			(layer "F.Fab")
		)
		(fp_line
			(start 0.12065 -0.2794)
			(end 0.12065 -0.3048)
			(stroke
				(width 0.1)
				(type default)
			)
			(layer "F.Fab")
		)
		(fp_line
			(start 0.12065 -0.3048)
			(end 0.67945 -0.3048)
			(stroke
				(width 0.1)
				(type default)
			)
			(layer "F.Fab")
		)
		(fp_line
			(start 0.120396 0.3048)
			(end 0.120396 0.2794)
			(stroke
				(width 0.1)
				(type default)
			)
			(layer "F.Fab")
		)
		(fp_line
			(start 0.120396 0.2794)
			(end -0.12065 0.2794)
			(stroke
				(width 0.1)
				(type default)
			)
			(layer "F.Fab")
		)
		(fp_line
			(start -0.12065 0.3048)
			(end -0.67945 0.3048)
			(stroke
				(width 0.1)
				(type default)
			)
			(layer "F.Fab")
		)
		(fp_line
			(start -0.12065 0.2794)
			(end -0.12065 0.3048)
			(stroke
				(width 0.1)
				(type default)
			)
			(layer "F.Fab")
		)
		(fp_line
			(start -0.12065 -0.2794)
			(end 0.12065 -0.2794)
			(stroke
				(width 0.1)
				(type default)
			)
			(layer "F.Fab")
		)
		(fp_line
			(start -0.12065 -0.305054)
			(end -0.12065 -0.2794)
			(stroke
				(width 0.1)
				(type default)
			)
			(layer "F.Fab")
		)
		(fp_line
			(start -0.67945 0.3048)
			(end -0.67945 -0.305054)
			(stroke
				(width 0.1)
				(type default)
			)
			(layer "F.Fab")
		)
		(fp_line
			(start -0.67945 -0.305054)
			(end -0.12065 -0.305054)
			(stroke
				(width 0.1)
				(type default)
			)
			(layer "F.Fab")
		)
		(pad "1" smd circle
			(at -0.40005 0 180)
			(size 0 0)
			(layers "F.Cu" "F.Mask" "F.Paste")
			(net "HDT_HDR_DBREQ_R_N")
		)
		(pad "2" smd circle
			(at 0.40005 0 180)
			(size 0 0)
			(layers "F.Cu" "F.Mask" "F.Paste")
			(net "HDT_HDR_DBREQ_N")
		)
	)
)
